(kicad_pcb
	(version 20260206)
	(generator "pcbnew")
	(generator_version "10.0")
	(general
		(thickness 1.6)
		(legacy_teardrops no)
	)
	(paper "A4")
	(title_block
		(title "panther-plus-userver — 13130-1b_20150205.brd")
		(comment 1 "Honey Badger (Wiwynn) / footprint 406 of 1509 (DIMM2), pads 177-183 of 210")
	)
	(layers
		(0 "F.Cu" signal "TOP")
		(4 "In1.Cu" signal "L2")
		(6 "In2.Cu" signal "L3")
		(8 "In3.Cu" signal "L4")
		(10 "In4.Cu" signal "L5")
		(12 "In5.Cu" signal "L6")
		(14 "In6.Cu" signal "L7")
		(16 "In7.Cu" signal "L8")
		(18 "In8.Cu" signal "L9")
		(20 "In9.Cu" signal "L10")
		(22 "In10.Cu" signal "L11")
		(2 "B.Cu" signal "BOTTOM")
		(9 "F.Adhes" user "F.Adhesive")
		(11 "B.Adhes" user "B.Adhesive")
		(13 "F.Paste" user "Package Geometry/Pastemask Top")
		(15 "B.Paste" user "Package Geometry/Pastemask Bottom")
		(5 "F.SilkS" user "Ref Des/Silkscreen Top")
		(7 "B.SilkS" user "Ref Des/Silkscreen Bottom")
		(1 "F.Mask" user "Board Geometry/Soldermask Top")
		(3 "B.Mask" user "Board Geometry/Soldermask Bottom")
		(17 "Dwgs.User" user "User.Drawings")
		(19 "Cmts.User" user "User.Comments")
		(21 "Eco1.User" user "User.Eco1")
		(23 "Eco2.User" user "User.Eco2")
		(25 "Edge.Cuts" user "Board Geometry/Outline")
		(27 "Margin" user)
		(31 "F.CrtYd" user "Package Geometry/Place Bound Top")
		(29 "B.CrtYd" user "Package Geometry/Place Bound Bottom")
		(35 "F.Fab" user "Ref Des/Assembly Top")
		(33 "B.Fab" user "Ref Des/Assembly Bottom")
	)
	(footprint ""
		(layer "F.Cu")
		(at 158.500064 -66.699892 180)
		(property "Reference" "DIMM2"
			(at 0 0 180)
			(layer "F.SilkS")
			(hide yes)
			(effects
				(font
					(size 1.27 1.27)
				)
			)
		)
		(property "Value" "DDR3-204P-174-COLAY-1-GP"
			(at -40.682164 -17.468088 180)
			(unlocked yes)
			(layer "F.Fab")
			(hide yes)
			(effects
				(font
					(size 1.016 1.016)
					(thickness 0.1524)
				)
			)
		)
		(property "Device Type" "AS0A626-H8SN-7H-COLAY-1"
			(at -40.682164 -18.992088 180)
			(unlocked yes)
			(layer "F.Fab")
			(hide yes)
			(effects
				(font
					(size 1.016 1.016)
					(thickness 0.1524)
				)
			)
		)
		(duplicate_pad_numbers_are_jumpers no)
		(pad "175" smd custom
			(at 22.949916 4.106672 180)
			(size 0.1143 0.1143)
			(layers "F.Cu" "F.Mask" "F.Paste")
			(net "GND")
			(options
				(clearance outline)
				(anchor circle)
			)
			(primitives
				(gr_poly
					(pts
						(xy 0 0.9017) (xy -0.03175 0.89916) (xy -0.0635 0.889) (xy -0.09144 0.87376) (xy -0.11684 0.85344)
						(xy -0.13716 0.82804) (xy -0.1524 0.8001) (xy -0.16256 0.76835) (xy -0.1651 0.7366) (xy -0.1651 0.11938)
						(xy -0.17272 0.11176) (xy -0.19812 0.0762) (xy -0.2032 0.06604) (xy -0.20701 0.05715) (xy -0.21209 0.04699)
						(xy -0.2159 0.03683) (xy -0.21844 0.02667) (xy -0.22225 0.01524) (xy -0.22352 0.00508) (xy -0.22606 -0.00508)
						(xy -0.22733 -0.01651) (xy -0.22733 -0.02667) (xy -0.2286 -0.0381) (xy -0.22733 -0.04953) (xy -0.22733 -0.05969)
						(xy -0.22606 -0.07112) (xy -0.22352 -0.08128) (xy -0.22225 -0.09144) (xy -0.21844 -0.10287) (xy -0.2159 -0.11303)
						(xy -0.21209 -0.12319) (xy -0.20701 -0.13335) (xy -0.2032 -0.14224) (xy -0.19812 -0.1524) (xy -0.17272 -0.18796)
						(xy -0.1651 -0.19558) (xy -0.1651 -0.7366) (xy -0.16256 -0.76835) (xy -0.1524 -0.8001) (xy -0.13716 -0.82804)
						(xy -0.11684 -0.85344) (xy -0.09144 -0.87376) (xy -0.0635 -0.889) (xy -0.03175 -0.89916) (xy 0 -0.9017)
						(xy 0.03175 -0.89916) (xy 0.0635 -0.889) (xy 0.09144 -0.87376) (xy 0.11684 -0.85344) (xy 0.13716 -0.82804)
						(xy 0.1524 -0.8001) (xy 0.16256 -0.76835) (xy 0.1651 -0.7366) (xy 0.1651 -0.19685) (xy 0.17272 -0.18923)
						(xy 0.17907 -0.18034) (xy 0.18669 -0.17145) (xy 0.19177 -0.16256) (xy 0.19812 -0.15367) (xy 0.20828 -0.13335)
						(xy 0.21971 -0.10287) (xy 0.22225 -0.09271) (xy 0.22479 -0.08128) (xy 0.22606 -0.07112) (xy 0.2286 -0.05969)
						(xy 0.2286 -0.01651) (xy 0.22606 -0.00508) (xy 0.22479 0.00508) (xy 0.22225 0.01651) (xy 0.21971 0.02667)
						(xy 0.20828 0.05715) (xy 0.19812 0.07747) (xy 0.19177 0.08636) (xy 0.18669 0.09525) (xy 0.17907 0.10414)
						(xy 0.17272 0.11303) (xy 0.1651 0.12065) (xy 0.1651 0.7366) (xy 0.16256 0.76835) (xy 0.1524 0.8001)
						(xy 0.13716 0.82804) (xy 0.11684 0.85344) (xy 0.09144 0.87376) (xy 0.0635 0.889) (xy 0.03175 0.89916)
					)
					(width 0)
					(fill yes)
				)
			)
		)
		(pad "176" smd custom
			(at 23.24989 -4.106672 180)
			(size 0.1143 0.1143)
			(layers "F.Cu" "F.Mask" "F.Paste")
			(net "M_A_DQ51")
			(options
				(clearance outline)
				(anchor circle)
			)
			(primitives
				(gr_poly
					(pts
						(xy 0 0.9017) (xy -0.03175 0.89916) (xy -0.0635 0.889) (xy -0.09144 0.87376) (xy -0.11684 0.85344)
						(xy -0.13716 0.82804) (xy -0.1524 0.8001) (xy -0.16256 0.76835) (xy -0.1651 0.7366) (xy -0.1651 0.19685)
						(xy -0.17272 0.18923) (xy -0.17907 0.18034) (xy -0.18669 0.17145) (xy -0.19177 0.16256) (xy -0.19812 0.15367)
						(xy -0.20828 0.13335) (xy -0.21971 0.10287) (xy -0.22225 0.09271) (xy -0.22479 0.08128) (xy -0.22606 0.07112)
						(xy -0.2286 0.05969) (xy -0.2286 0.01651) (xy -0.22606 0.00508) (xy -0.22479 -0.00508) (xy -0.22225 -0.01651)
						(xy -0.21971 -0.02667) (xy -0.20828 -0.05715) (xy -0.19812 -0.07747) (xy -0.19177 -0.08636) (xy -0.18669 -0.09525)
						(xy -0.17907 -0.10414) (xy -0.17272 -0.11303) (xy -0.1651 -0.12065) (xy -0.1651 -0.7366) (xy -0.16256 -0.76835)
						(xy -0.1524 -0.8001) (xy -0.13716 -0.82804) (xy -0.11684 -0.85344) (xy -0.09144 -0.87376) (xy -0.0635 -0.889)
						(xy -0.03175 -0.89916) (xy 0 -0.9017) (xy 0.03175 -0.89916) (xy 0.0635 -0.889) (xy 0.09144 -0.87376)
						(xy 0.11684 -0.85344) (xy 0.13716 -0.82804) (xy 0.1524 -0.8001) (xy 0.16256 -0.76835) (xy 0.1651 -0.7366)
						(xy 0.1651 -0.11938) (xy 0.17272 -0.11176) (xy 0.19812 -0.0762) (xy 0.2032 -0.06604) (xy 0.20701 -0.05715)
						(xy 0.21209 -0.04699) (xy 0.2159 -0.03683) (xy 0.21844 -0.02667) (xy 0.22225 -0.01524) (xy 0.22352 -0.00508)
						(xy 0.22606 0.00508) (xy 0.22733 0.01651) (xy 0.22733 0.02667) (xy 0.2286 0.0381) (xy 0.22733 0.04953)
						(xy 0.22733 0.05969) (xy 0.22606 0.07112) (xy 0.22352 0.08128) (xy 0.22225 0.09144) (xy 0.21844 0.10287)
						(xy 0.2159 0.11303) (xy 0.21209 0.12319) (xy 0.20701 0.13335) (xy 0.2032 0.14224) (xy 0.19812 0.1524)
						(xy 0.17272 0.18796) (xy 0.1651 0.19558) (xy 0.1651 0.7366) (xy 0.16256 0.76835) (xy 0.1524 0.8001)
						(xy 0.13716 0.82804) (xy 0.11684 0.85344) (xy 0.09144 0.87376) (xy 0.0635 0.889) (xy 0.03175 0.89916)
					)
					(width 0)
					(fill yes)
				)
			)
		)
		(pad "177" smd custom
			(at 23.550118 4.106672 180)
			(size 0.1143 0.1143)
			(layers "F.Cu" "F.Mask" "F.Paste")
			(net "M_A_DQ54")
			(options
				(clearance outline)
				(anchor circle)
			)
			(primitives
				(gr_poly
					(pts
						(xy 0 0.9017) (xy -0.03175 0.89916) (xy -0.0635 0.889) (xy -0.09144 0.87376) (xy -0.11684 0.85344)
						(xy -0.13716 0.82804) (xy -0.1524 0.8001) (xy -0.16256 0.76835) (xy -0.1651 0.7366) (xy -0.1651 -0.13462)
						(xy -0.17272 -0.14224) (xy -0.19812 -0.1778) (xy -0.2032 -0.18796) (xy -0.20701 -0.19685) (xy -0.21209 -0.20701)
						(xy -0.2159 -0.21717) (xy -0.21844 -0.22733) (xy -0.22225 -0.23876) (xy -0.22352 -0.24892) (xy -0.22606 -0.25908)
						(xy -0.22733 -0.27051) (xy -0.22733 -0.28067) (xy -0.2286 -0.2921) (xy -0.22733 -0.30353) (xy -0.22733 -0.31369)
						(xy -0.22606 -0.32512) (xy -0.22352 -0.33528) (xy -0.22225 -0.34544) (xy -0.21844 -0.35687) (xy -0.2159 -0.36703)
						(xy -0.21209 -0.37719) (xy -0.20701 -0.38735) (xy -0.2032 -0.39624) (xy -0.19812 -0.4064) (xy -0.17272 -0.44196)
						(xy -0.1651 -0.44958) (xy -0.1651 -0.7366) (xy -0.16256 -0.76835) (xy -0.1524 -0.8001) (xy -0.13716 -0.82804)
						(xy -0.11684 -0.85344) (xy -0.09144 -0.87376) (xy -0.0635 -0.889) (xy -0.03175 -0.89916) (xy 0 -0.9017)
						(xy 0.03175 -0.89916) (xy 0.0635 -0.889) (xy 0.09144 -0.87376) (xy 0.11684 -0.85344) (xy 0.13716 -0.82804)
						(xy 0.1524 -0.8001) (xy 0.16256 -0.76835) (xy 0.1651 -0.7366) (xy 0.1651 -0.44958) (xy 0.17272 -0.44196)
						(xy 0.19812 -0.4064) (xy 0.2032 -0.39624) (xy 0.20701 -0.38735) (xy 0.21209 -0.37719) (xy 0.2159 -0.36703)
						(xy 0.21844 -0.35687) (xy 0.22225 -0.34544) (xy 0.22352 -0.33528) (xy 0.22606 -0.32512) (xy 0.22733 -0.31369)
						(xy 0.22733 -0.30353) (xy 0.2286 -0.2921) (xy 0.22733 -0.28067) (xy 0.22733 -0.27051) (xy 0.22606 -0.25908)
						(xy 0.22352 -0.24892) (xy 0.22225 -0.23876) (xy 0.21844 -0.22733) (xy 0.2159 -0.21717) (xy 0.21209 -0.20701)
						(xy 0.20701 -0.19685) (xy 0.2032 -0.18796) (xy 0.19812 -0.1778) (xy 0.17272 -0.14224) (xy 0.1651 -0.13462)
						(xy 0.1651 0.7366) (xy 0.16256 0.76835) (xy 0.1524 0.8001) (xy 0.13716 0.82804) (xy 0.11684 0.85344)
						(xy 0.09144 0.87376) (xy 0.0635 0.889) (xy 0.03175 0.89916)
					)
					(width 0)
					(fill yes)
				)
			)
		)
		(pad "178" smd custom
			(at 23.850092 -4.106672 180)
			(size 0.1143 0.1143)
			(layers "F.Cu" "F.Mask" "F.Paste")
			(net "GND")
			(options
				(clearance outline)
				(anchor circle)
			)
			(primitives
				(gr_poly
					(pts
						(xy 0 0.9017) (xy -0.03175 0.89916) (xy -0.0635 0.889) (xy -0.09144 0.87376) (xy -0.11684 0.85344)
						(xy -0.13716 0.82804) (xy -0.1524 0.8001) (xy -0.16256 0.76835) (xy -0.1651 0.7366) (xy -0.1651 0.44958)
						(xy -0.17272 0.44196) (xy -0.19812 0.4064) (xy -0.2032 0.39624) (xy -0.20701 0.38735) (xy -0.21209 0.37719)
						(xy -0.2159 0.36703) (xy -0.21844 0.35687) (xy -0.22225 0.34544) (xy -0.22352 0.33528) (xy -0.22606 0.32512)
						(xy -0.22733 0.31369) (xy -0.22733 0.30353) (xy -0.2286 0.2921) (xy -0.22733 0.28067) (xy -0.22733 0.27051)
						(xy -0.22606 0.25908) (xy -0.22352 0.24892) (xy -0.22225 0.23876) (xy -0.21844 0.22733) (xy -0.2159 0.21717)
						(xy -0.21209 0.20701) (xy -0.20701 0.19685) (xy -0.2032 0.18796) (xy -0.19812 0.1778) (xy -0.17272 0.14224)
						(xy -0.1651 0.13462) (xy -0.1651 -0.7366) (xy -0.16256 -0.76835) (xy -0.1524 -0.8001) (xy -0.13716 -0.82804)
						(xy -0.11684 -0.85344) (xy -0.09144 -0.87376) (xy -0.0635 -0.889) (xy -0.03175 -0.89916) (xy 0 -0.9017)
						(xy 0.03175 -0.89916) (xy 0.0635 -0.889) (xy 0.09144 -0.87376) (xy 0.11684 -0.85344) (xy 0.13716 -0.82804)
						(xy 0.1524 -0.8001) (xy 0.16256 -0.76835) (xy 0.1651 -0.7366) (xy 0.1651 0.13462) (xy 0.17272 0.14224)
						(xy 0.19812 0.1778) (xy 0.2032 0.18796) (xy 0.20701 0.19685) (xy 0.21209 0.20701) (xy 0.2159 0.21717)
						(xy 0.21844 0.22733) (xy 0.22225 0.23876) (xy 0.22352 0.24892) (xy 0.22606 0.25908) (xy 0.22733 0.27051)
						(xy 0.22733 0.28067) (xy 0.2286 0.2921) (xy 0.22733 0.30353) (xy 0.22733 0.31369) (xy 0.22606 0.32512)
						(xy 0.22352 0.33528) (xy 0.22225 0.34544) (xy 0.21844 0.35687) (xy 0.2159 0.36703) (xy 0.21209 0.37719)
						(xy 0.20701 0.38735) (xy 0.2032 0.39624) (xy 0.19812 0.4064) (xy 0.17272 0.44196) (xy 0.1651 0.44958)
						(xy 0.1651 0.7366) (xy 0.16256 0.76835) (xy 0.1524 0.8001) (xy 0.13716 0.82804) (xy 0.11684 0.85344)
						(xy 0.09144 0.87376) (xy 0.0635 0.889) (xy 0.03175 0.89916)
					)
					(width 0)
					(fill yes)
				)
			)
		)
		(pad "179" smd custom
			(at 24.150066 4.106672 180)
			(size 0.1143 0.1143)
			(layers "F.Cu" "F.Mask" "F.Paste")
			(net "M_A_DQ55")
			(options
				(clearance outline)
				(anchor circle)
			)
			(primitives
				(gr_poly
					(pts
						(xy 0 0.9017) (xy -0.03175 0.89916) (xy -0.0635 0.889) (xy -0.09144 0.87376) (xy -0.11684 0.85344)
						(xy -0.13716 0.82804) (xy -0.1524 0.8001) (xy -0.16256 0.76835) (xy -0.1651 0.7366) (xy -0.1651 0.11938)
						(xy -0.17272 0.11176) (xy -0.19812 0.0762) (xy -0.2032 0.06604) (xy -0.20701 0.05715) (xy -0.21209 0.04699)
						(xy -0.2159 0.03683) (xy -0.21844 0.02667) (xy -0.22225 0.01524) (xy -0.22352 0.00508) (xy -0.22606 -0.00508)
						(xy -0.22733 -0.01651) (xy -0.22733 -0.02667) (xy -0.2286 -0.0381) (xy -0.22733 -0.04953) (xy -0.22733 -0.05969)
						(xy -0.22606 -0.07112) (xy -0.22352 -0.08128) (xy -0.22225 -0.09144) (xy -0.21844 -0.10287) (xy -0.2159 -0.11303)
						(xy -0.21209 -0.12319) (xy -0.20701 -0.13335) (xy -0.2032 -0.14224) (xy -0.19812 -0.1524) (xy -0.17272 -0.18796)
						(xy -0.1651 -0.19558) (xy -0.1651 -0.7366) (xy -0.16256 -0.76835) (xy -0.1524 -0.8001) (xy -0.13716 -0.82804)
						(xy -0.11684 -0.85344) (xy -0.09144 -0.87376) (xy -0.0635 -0.889) (xy -0.03175 -0.89916) (xy 0 -0.9017)
						(xy 0.03175 -0.89916) (xy 0.0635 -0.889) (xy 0.09144 -0.87376) (xy 0.11684 -0.85344) (xy 0.13716 -0.82804)
						(xy 0.1524 -0.8001) (xy 0.16256 -0.76835) (xy 0.1651 -0.7366) (xy 0.1651 -0.19685) (xy 0.17272 -0.18923)
						(xy 0.17907 -0.18034) (xy 0.18669 -0.17145) (xy 0.19177 -0.16256) (xy 0.19812 -0.15367) (xy 0.20828 -0.13335)
						(xy 0.21971 -0.10287) (xy 0.22225 -0.09271) (xy 0.22479 -0.08128) (xy 0.22606 -0.07112) (xy 0.2286 -0.05969)
						(xy 0.2286 -0.01651) (xy 0.22606 -0.00508) (xy 0.22479 0.00508) (xy 0.22225 0.01651) (xy 0.21971 0.02667)
						(xy 0.20828 0.05715) (xy 0.19812 0.07747) (xy 0.19177 0.08636) (xy 0.18669 0.09525) (xy 0.17907 0.10414)
						(xy 0.17272 0.11303) (xy 0.1651 0.12065) (xy 0.1651 0.7366) (xy 0.16256 0.76835) (xy 0.1524 0.8001)
						(xy 0.13716 0.82804) (xy 0.11684 0.85344) (xy 0.09144 0.87376) (xy 0.0635 0.889) (xy 0.03175 0.89916)
					)
					(width 0)
					(fill yes)
				)
			)
		)
		(pad "180" smd custom
			(at 24.45004 -4.106672 180)
			(size 0.1143 0.1143)
			(layers "F.Cu" "F.Mask" "F.Paste")
			(net "M_A_DQ56")
			(options
				(clearance outline)
				(anchor circle)
			)
			(primitives
				(gr_poly
					(pts
						(xy 0 0.9017) (xy -0.03175 0.89916) (xy -0.0635 0.889) (xy -0.09144 0.87376) (xy -0.11684 0.85344)
						(xy -0.13716 0.82804) (xy -0.1524 0.8001) (xy -0.16256 0.76835) (xy -0.1651 0.7366) (xy -0.1651 0.19685)
						(xy -0.17272 0.18923) (xy -0.17907 0.18034) (xy -0.18669 0.17145) (xy -0.19177 0.16256) (xy -0.19812 0.15367)
						(xy -0.20828 0.13335) (xy -0.21971 0.10287) (xy -0.22225 0.09271) (xy -0.22479 0.08128) (xy -0.22606 0.07112)
						(xy -0.2286 0.05969) (xy -0.2286 0.01651) (xy -0.22606 0.00508) (xy -0.22479 -0.00508) (xy -0.22225 -0.01651)
						(xy -0.21971 -0.02667) (xy -0.20828 -0.05715) (xy -0.19812 -0.07747) (xy -0.19177 -0.08636) (xy -0.18669 -0.09525)
						(xy -0.17907 -0.10414) (xy -0.17272 -0.11303) (xy -0.1651 -0.12065) (xy -0.1651 -0.7366) (xy -0.16256 -0.76835)
						(xy -0.1524 -0.8001) (xy -0.13716 -0.82804) (xy -0.11684 -0.85344) (xy -0.09144 -0.87376) (xy -0.0635 -0.889)
						(xy -0.03175 -0.89916) (xy 0 -0.9017) (xy 0.03175 -0.89916) (xy 0.0635 -0.889) (xy 0.09144 -0.87376)
						(xy 0.11684 -0.85344) (xy 0.13716 -0.82804) (xy 0.1524 -0.8001) (xy 0.16256 -0.76835) (xy 0.1651 -0.7366)
						(xy 0.1651 -0.11938) (xy 0.17272 -0.11176) (xy 0.19812 -0.0762) (xy 0.2032 -0.06604) (xy 0.20701 -0.05715)
						(xy 0.21209 -0.04699) (xy 0.2159 -0.03683) (xy 0.21844 -0.02667) (xy 0.22225 -0.01524) (xy 0.22352 -0.00508)
						(xy 0.22606 0.00508) (xy 0.22733 0.01651) (xy 0.22733 0.02667) (xy 0.2286 0.0381) (xy 0.22733 0.04953)
						(xy 0.22733 0.05969) (xy 0.22606 0.07112) (xy 0.22352 0.08128) (xy 0.22225 0.09144) (xy 0.21844 0.10287)
						(xy 0.2159 0.11303) (xy 0.21209 0.12319) (xy 0.20701 0.13335) (xy 0.2032 0.14224) (xy 0.19812 0.1524)
						(xy 0.17272 0.18796) (xy 0.1651 0.19558) (xy 0.1651 0.7366) (xy 0.16256 0.76835) (xy 0.1524 0.8001)
						(xy 0.13716 0.82804) (xy 0.11684 0.85344) (xy 0.09144 0.87376) (xy 0.0635 0.889) (xy 0.03175 0.89916)
					)
					(width 0)
					(fill yes)
				)
			)
		)
		(pad "181" smd custom
			(at 24.750014 4.106672 180)
			(size 0.1143 0.1143)
			(layers "F.Cu" "F.Mask" "F.Paste")
			(net "GND")
			(options
				(clearance outline)
				(anchor circle)
			)
			(primitives
				(gr_poly
					(pts
						(xy 0 0.9017) (xy -0.03175 0.89916) (xy -0.0635 0.889) (xy -0.09144 0.87376) (xy -0.11684 0.85344)
						(xy -0.13716 0.82804) (xy -0.1524 0.8001) (xy -0.16256 0.76835) (xy -0.1651 0.7366) (xy -0.1651 -0.13462)
						(xy -0.17272 -0.14224) (xy -0.19812 -0.1778) (xy -0.2032 -0.18796) (xy -0.20701 -0.19685) (xy -0.21209 -0.20701)
						(xy -0.2159 -0.21717) (xy -0.21844 -0.22733) (xy -0.22225 -0.23876) (xy -0.22352 -0.24892) (xy -0.22606 -0.25908)
						(xy -0.22733 -0.27051) (xy -0.22733 -0.28067) (xy -0.2286 -0.2921) (xy -0.22733 -0.30353) (xy -0.22733 -0.31369)
						(xy -0.22606 -0.32512) (xy -0.22352 -0.33528) (xy -0.22225 -0.34544) (xy -0.21844 -0.35687) (xy -0.2159 -0.36703)
						(xy -0.21209 -0.37719) (xy -0.20701 -0.38735) (xy -0.2032 -0.39624) (xy -0.19812 -0.4064) (xy -0.17272 -0.44196)
						(xy -0.1651 -0.44958) (xy -0.1651 -0.7366) (xy -0.16256 -0.76835) (xy -0.1524 -0.8001) (xy -0.13716 -0.82804)
						(xy -0.11684 -0.85344) (xy -0.09144 -0.87376) (xy -0.0635 -0.889) (xy -0.03175 -0.89916) (xy 0 -0.9017)
						(xy 0.03175 -0.89916) (xy 0.0635 -0.889) (xy 0.09144 -0.87376) (xy 0.11684 -0.85344) (xy 0.13716 -0.82804)
						(xy 0.1524 -0.8001) (xy 0.16256 -0.76835) (xy 0.1651 -0.7366) (xy 0.1651 -0.44958) (xy 0.17272 -0.44196)
						(xy 0.19812 -0.4064) (xy 0.2032 -0.39624) (xy 0.20701 -0.38735) (xy 0.21209 -0.37719) (xy 0.2159 -0.36703)
						(xy 0.21844 -0.35687) (xy 0.22225 -0.34544) (xy 0.22352 -0.33528) (xy 0.22606 -0.32512) (xy 0.22733 -0.31369)
						(xy 0.22733 -0.30353) (xy 0.2286 -0.2921) (xy 0.22733 -0.28067) (xy 0.22733 -0.27051) (xy 0.22606 -0.25908)
						(xy 0.22352 -0.24892) (xy 0.22225 -0.23876) (xy 0.21844 -0.22733) (xy 0.2159 -0.21717) (xy 0.21209 -0.20701)
						(xy 0.20701 -0.19685) (xy 0.2032 -0.18796) (xy 0.19812 -0.1778) (xy 0.17272 -0.14224) (xy 0.1651 -0.13462)
						(xy 0.1651 0.7366) (xy 0.16256 0.76835) (xy 0.1524 0.8001) (xy 0.13716 0.82804) (xy 0.11684 0.85344)
						(xy 0.09144 0.87376) (xy 0.0635 0.889) (xy 0.03175 0.89916)
					)
					(width 0)
					(fill yes)
				)
			)
		)
	)
)
